FILE_TYPE=LIBRARY_PARTS;
primitive 'PCA9545APW';
  pin
    'A0':
      PIN_NUMBER='(1)';
      INPUT_LOAD='(-0.01,0.01)';
    'A1':
      PIN_NUMBER='(2)';
      INPUT_LOAD='(-0.01,0.01)';
    'RESET#':
      PIN_NUMBER='(3)';
      INPUT_LOAD='(-0.01,0.01)';
    'INT#':
      PIN_NUMBER='(17)';
      OUTPUT_LOAD='(1.0,-1.0)';
    'SCL':
      PIN_NUMBER='(18)';
      INPUT_LOAD='(-0.01,0.01)';
    'SDA':
      PIN_NUMBER='(19)';
      BIDIRECTIONAL='TRUE';
      INPUT_LOAD='(-0.01,0.01)';
      OUTPUT_LOAD='(1.0,-1.0)';
    'VSS':
      PIN_NUMBER='(10)';
      PINUSE='POWER';
      NO_LOAD_CHECK='Both';
      NO_IO_CHECK='Both';
      NO_ASSERT_CHECK='TRUE';
      NO_DIR_CHECK='TRUE';
      ALLOW_CONNECT='TRUE';
    'VDD':
      PIN_NUMBER='(20)';
      PINUSE='POWER';
      NO_LOAD_CHECK='Both';
      NO_IO_CHECK='Both';
      NO_ASSERT_CHECK='TRUE';
      NO_DIR_CHECK='TRUE';
      ALLOW_CONNECT='TRUE';
    'SD0':
      PIN_NUMBER='(5)';
      BIDIRECTIONAL='TRUE';
      INPUT_LOAD='(-0.01,0.01)';
      OUTPUT_LOAD='(1.0,-1.0)';
    'SC0':
      PIN_NUMBER='(6)';
      INPUT_LOAD='(-0.01,0.01)';
    'INT0#':
      PIN_NUMBER='(4)';
      INPUT_LOAD='(-0.01,0.01)';
    'SD1':
      PIN_NUMBER='(8)';
      BIDIRECTIONAL='TRUE';
      INPUT_LOAD='(-0.01,0.01)';
      OUTPUT_LOAD='(1.0,-1.0)';
    'SC1':
      PIN_NUMBER='(9)';
      INPUT_LOAD='(-0.01,0.01)';
    'INT1#':
      PIN_NUMBER='(7)';
      INPUT_LOAD='(-0.01,0.01)';
    'SD2':
      PIN_NUMBER='(12)';
      BIDIRECTIONAL='TRUE';
      INPUT_LOAD='(-0.01,0.01)';
      OUTPUT_LOAD='(1.0,-1.0)';
    'SC2':
      PIN_NUMBER='(13)';
      INPUT_LOAD='(-0.01,0.01)';
    'INT2#':
      PIN_NUMBER='(11)';
      INPUT_LOAD='(-0.01,0.01)';
    'SD3':
      PIN_NUMBER='(15)';
      BIDIRECTIONAL='TRUE';
      INPUT_LOAD='(-0.01,0.01)';
      OUTPUT_LOAD='(1.0,-1.0)';
    'SC3':
      PIN_NUMBER='(16)';
      INPUT_LOAD='(-0.01,0.01)';
    'INT3#':
      PIN_NUMBER='(14)';
      INPUT_LOAD='(-0.01,0.01)';
  end_pin;
  body
    PART_NAME='PCA9545APW';
    BODY_NAME='PCA9545APW';
    PHYS_DES_PREFIX='U';
    CLASS='IC';
  end_body;
end_primitive;

END.
